# BASEBOARD_FAB2 (Tioga Pass) — schematic netlist excerpt (pin names and nets, part order shuffled) for the footprints in the layout excerpt that follows; sources: Cadence DE-HDL packaged netlist, KiCad conversion of Wiwynn_Tioga_Pass_MB.brd

R1U2  RES  100.0K 1% CHIP  pkg 0402  page 147 : A = FAN_TACH2 ; B = GND
T1P32  TPAD-SE-2P-GP  pkg DISCRET-GA1  page 256 : \1\ = L3_50OHM_6INCH ; GND1 = GND

(kicad_pcb
	(version 20260206)
	(generator "pcbnew")
	(generator_version "10.0")
	(general
		(thickness 1.6)
		(legacy_teardrops no)
	)
	(paper "A4")
	(title_block
		(title "Wiwynn_Tioga_Pass_MB.brd")
		(comment 1 "Tioga Pass / footprints 947-948 of 4770")
	)
	(layers
		(0 "F.Cu" signal "TOP")
		(4 "In1.Cu" signal "L2GND")
		(6 "In2.Cu" signal "L3")
		(8 "In3.Cu" signal "L4GND")
		(10 "In4.Cu" signal "L5")
		(12 "In5.Cu" signal "L6GND")
		(14 "In6.Cu" signal "L7VCC")
		(16 "In7.Cu" signal "L8VCC")
		(18 "In8.Cu" signal "L9GND")
		(20 "In9.Cu" signal "L10")
		(22 "In10.Cu" signal "L11GND")
		(24 "In11.Cu" signal "L12")
		(26 "In12.Cu" signal "L13GND")
		(2 "B.Cu" signal "BOTTOM")
		(9 "F.Adhes" user "F.Adhesive")
		(11 "B.Adhes" user "B.Adhesive")
		(13 "F.Paste" user "Package Geometry/Pastemask Top")
		(15 "B.Paste" user "Package Geometry/Pastemask Bottom")
		(5 "F.SilkS" user "Ref Des/Silkscreen Top")
		(7 "B.SilkS" user "Ref Des/Silkscreen Bottom")
		(1 "F.Mask" user "Board Geometry/Soldermask Top")
		(3 "B.Mask" user "Board Geometry/Soldermask Bottom")
		(17 "Dwgs.User" user "User.Drawings")
		(19 "Cmts.User" user "User.Comments")
		(21 "Eco1.User" user "User.Eco1")
		(23 "Eco2.User" user "User.Eco2")
		(25 "Edge.Cuts" user "Board Geometry/Outline")
		(27 "Margin" user)
		(31 "F.CrtYd" user "Package Geometry/Place Bound Top")
		(29 "B.CrtYd" user "Package Geometry/Place Bound Bottom")
		(35 "F.Fab" user "Ref Des/Assembly Top")
		(33 "B.Fab" user "Ref Des/Assembly Bottom")
	)
	(footprint ""
		(layer "F.Cu")
		(at 14.097 13.2715 -90)
		(property "Reference" "T1P32"
			(at 0 0 270)
			(layer "F.SilkS")
			(hide yes)
			(effects
				(font
					(size 1.27 1.27)
				)
			)
		)
		(property "Value" "*"
			(at 0 -3.44805 270)
			(unlocked yes)
			(layer "F.Fab")
			(hide yes)
			(effects
				(font
					(size 0.889 0.889)
					(thickness 0.1524)
				)
			)
		)
		(property "Device Type" "TPAD-SE-2P-GP_DISCRET-GA1-TPADA"
			(at 0 -4.97205 270)
			(unlocked yes)
			(layer "F.Fab")
			(hide yes)
			(effects
				(font
					(size 0.889 0.889)
					(thickness 0.1524)
				)
			)
		)
		(duplicate_pad_numbers_are_jumpers no)
		(fp_line
			(start -1.016 2.286)
			(end -1.016 -2.286)
			(stroke
				(width 0.1524)
				(type default)
			)
			(layer "F.SilkS")
		)
		(fp_line
			(start 1.016 2.286)
			(end -1.016 2.286)
			(stroke
				(width 0.1524)
				(type default)
			)
			(layer "F.SilkS")
		)
		(fp_line
			(start -1.016 -2.286)
			(end 1.016 -2.286)
			(stroke
				(width 0.1524)
				(type default)
			)
			(layer "F.SilkS")
		)
		(fp_line
			(start 1.016 -2.286)
			(end 1.016 2.286)
			(stroke
				(width 0.1524)
				(type default)
			)
			(layer "F.SilkS")
		)
		(fp_rect
			(start -1.27 2.54)
			(end 1.27 -2.54)
			(stroke
				(width 0)
				(type default)
			)
			(fill no)
			(layer "F.CrtYd")
		)
		(fp_rect
			(start -1.27 2.54)
			(end 1.27 -2.54)
			(stroke
				(width 0)
				(type default)
			)
			(fill no)
			(layer "F.Fab")
		)
		(pad "1" thru_hole circle
			(at 0 -1.27 270)
			(size 1.524 1.524)
			(drill 0.9144)
			(layers "*.Cu" "*.Mask")
			(remove_unused_layers no)
			(net "L3_50OHM_6INCH")
			(clearance -0.0508)
			(thermal_gap 0.127)
			(padstack
				(mode front_inner_back)
				(layer "Inner"
					(shape circle)
					(size 1.1684 1.1684)
					(clearance 0.127)
				)
				(layer "B.Cu"
					(shape circle)
					(size 1.524 1.524)
					(clearance -0.0508)
				)
			)
		)
		(pad "GND1" thru_hole rect
			(at 0 1.27 270)
			(size 1.524 1.524)
			(drill 0.9144)
			(layers "*.Cu" "*.Mask")
			(remove_unused_layers no)
			(net "GND")
			(clearance -0.0508)
			(thermal_gap 0.127)
			(padstack
				(mode front_inner_back)
				(layer "Inner"
					(shape circle)
					(size 1.1684 1.1684)
					(clearance 0.127)
				)
				(layer "B.Cu"
					(shape rect)
					(size 1.524 1.524)
					(clearance -0.0508)
				)
			)
		)
	)
	(footprint ""
		(layer "F.Cu")
		(at 460.2226 -30.734)
		(property "Reference" "R1U2"
			(at 0 0 0)
			(layer "F.SilkS")
			(hide yes)
			(effects
				(font
					(size 1.27 1.27)
				)
			)
		)
		(property "Value" ""
			(at 0 0 0)
			(layer "F.Fab")
			(effects
				(font
					(size 1.27 1.27)
				)
			)
		)
		(duplicate_pad_numbers_are_jumpers no)
		(fp_poly
			(pts
				(xy -0.2794 -0.1016) (xy 0.2794 -0.1016) (xy 0.2794 0.9906) (xy -0.2794 0.9906)
			)
			(stroke
				(width 0)
				(type default)
			)
			(fill no)
			(layer "F.CrtYd")
		)
		(fp_line
			(start -0.2794 -0.1016)
			(end -0.2794 0.9906)
			(stroke
				(width 0.1)
				(type default)
			)
			(layer "F.Fab")
		)
		(fp_line
			(start -0.2794 0.9906)
			(end 0.2794 0.9906)
			(stroke
				(width 0.1)
				(type default)
			)
			(layer "F.Fab")
		)
		(fp_line
			(start 0.2794 -0.1016)
			(end -0.2794 -0.1016)
			(stroke
				(width 0.1)
				(type default)
			)
			(layer "F.Fab")
		)
		(fp_line
			(start 0.2794 0.9906)
			(end 0.2794 -0.1016)
			(stroke
				(width 0.1)
				(type default)
			)
			(layer "F.Fab")
		)
		(pad "1" smd rect
			(at 0 0)
			(size 0.508 0.508)
			(layers "F.Cu" "F.Mask" "F.Paste")
			(net "FAN_TACH2")
		)
		(pad "2" smd rect
			(at 0 0.889)
			(size 0.508 0.508)
			(layers "F.Cu" "F.Mask" "F.Paste")
			(net "GND")
		)
		(zone
			(layer "F.Cu")
			(hatch none 0.5)
			(connect_pads
				(clearance 0)
			)
			(min_thickness 0.25)
			(keepout
				(tracks allowed)
				(vias not_allowed)
				(pads allowed)
				(copperpour not_allowed)
				(footprints allowed)
			)
			(placement
				(enabled no)
				(sheetname "")
			)
			(fill
				(thermal_gap 0.5)
				(thermal_bridge_width 0.5)
				(island_removal_mode 0)
			)
			(polygon
				(pts
					(xy 459.9686 -30.48) (xy 460.4766 -30.48) (xy 460.4766 -30.099) (xy 459.9686 -30.099)
				)
			)
		)
		(zone
			(layer "F.Cu")
			(hatch none 0.5)
			(connect_pads
				(clearance 0)
			)
			(min_thickness 0.25)
			(keepout
				(tracks not_allowed)
				(vias allowed)
				(pads allowed)
				(copperpour not_allowed)
				(footprints allowed)
			)
			(placement
				(enabled no)
				(sheetname "")
			)
			(fill
				(thermal_gap 0.5)
				(thermal_bridge_width 0.5)
				(island_removal_mode 0)
			)
			(polygon
				(pts
					(xy 459.9686 -30.099) (xy 460.4766 -30.099) (xy 460.4766 -30.48) (xy 459.9686 -30.48)
				)
			)
		)
	)
)
